# BASEBOARD_FAB2 (Tioga Pass) — schematic netlist excerpt (pin names and nets, part order shuffled) for the footprints in the layout excerpt that follows; sources: Cadence DE-HDL packaged netlist, KiCad conversion of Wiwynn_Tioga_Pass_MB.brd

C4G19  CAP_A  0.01UF 25V 10% X7R  pkg 0402V  page 47 : A = M_C_VREF ; B = GND

T1D14  TEST-PAD-12P-1-GP-U  pkg DISCRET-GB1  page 258
  DP  = L1_85OHM_10INCH_DN
  DN  = L1_85OHM_10INCH_DP
  GND(0)  = GND
  GND(1)  = GND
  GND(2)  = GND
  GND(3)  = GND
  GND(4)  = GND
  GND(5)  = GND
  GND(6)  = GND
  GND(7)  = GND
  GND(8)  = GND
  GND(9)  = GND

(kicad_pcb
	(version 20260206)
	(generator "pcbnew")
	(generator_version "10.0")
	(general
		(thickness 1.6)
		(legacy_teardrops no)
	)
	(paper "A4")
	(title_block
		(title "Wiwynn_Tioga_Pass_MB.brd")
		(comment 1 "Tioga Pass / footprints 1016-1017 of 4770")
	)
	(layers
		(0 "F.Cu" signal "TOP")
		(4 "In1.Cu" signal "L2GND")
		(6 "In2.Cu" signal "L3")
		(8 "In3.Cu" signal "L4GND")
		(10 "In4.Cu" signal "L5")
		(12 "In5.Cu" signal "L6GND")
		(14 "In6.Cu" signal "L7VCC")
		(16 "In7.Cu" signal "L8VCC")
		(18 "In8.Cu" signal "L9GND")
		(20 "In9.Cu" signal "L10")
		(22 "In10.Cu" signal "L11GND")
		(24 "In11.Cu" signal "L12")
		(26 "In12.Cu" signal "L13GND")
		(2 "B.Cu" signal "BOTTOM")
		(9 "F.Adhes" user "F.Adhesive")
		(11 "B.Adhes" user "B.Adhesive")
		(13 "F.Paste" user "Package Geometry/Pastemask Top")
		(15 "B.Paste" user "Package Geometry/Pastemask Bottom")
		(5 "F.SilkS" user "Ref Des/Silkscreen Top")
		(7 "B.SilkS" user "Ref Des/Silkscreen Bottom")
		(1 "F.Mask" user "Board Geometry/Soldermask Top")
		(3 "B.Mask" user "Board Geometry/Soldermask Bottom")
		(17 "Dwgs.User" user "User.Drawings")
		(19 "Cmts.User" user "User.Comments")
		(21 "Eco1.User" user "User.Eco1")
		(23 "Eco2.User" user "User.Eco2")
		(25 "Edge.Cuts" user "Board Geometry/Outline")
		(27 "Margin" user)
		(31 "F.CrtYd" user "Package Geometry/Place Bound Top")
		(29 "B.CrtYd" user "Package Geometry/Place Bound Bottom")
		(35 "F.Fab" user "Ref Des/Assembly Top")
		(33 "B.Fab" user "Ref Des/Assembly Bottom")
	)
	(footprint ""
		(layer "F.Cu")
		(at 195.58 -3.321812 90)
		(property "Reference" "C4G19"
			(at 0 0 90)
			(layer "F.SilkS")
			(hide yes)
			(effects
				(font
					(size 1.27 1.27)
				)
			)
		)
		(property "Value" ""
			(at 0 0 90)
			(layer "F.Fab")
			(effects
				(font
					(size 1.27 1.27)
				)
			)
		)
		(duplicate_pad_numbers_are_jumpers no)
		(fp_poly
			(pts
				(xy 0.3048 -0.1016) (xy 0.3048 0.9906) (xy -0.3048 0.9906) (xy -0.3048 -0.1016)
			)
			(stroke
				(width 0)
				(type default)
			)
			(fill no)
			(layer "F.CrtYd")
		)
		(fp_line
			(start 0.3048 -0.1016)
			(end -0.3048 -0.1016)
			(stroke
				(width 0.1)
				(type default)
			)
			(layer "F.Fab")
		)
		(fp_line
			(start -0.3048 -0.1016)
			(end -0.3048 0.9906)
			(stroke
				(width 0.1)
				(type default)
			)
			(layer "F.Fab")
		)
		(fp_line
			(start 0.3048 0.9906)
			(end 0.3048 -0.1016)
			(stroke
				(width 0.1)
				(type default)
			)
			(layer "F.Fab")
		)
		(fp_line
			(start -0.3048 0.9906)
			(end 0.3048 0.9906)
			(stroke
				(width 0.1)
				(type default)
			)
			(layer "F.Fab")
		)
		(pad "1" smd rect
			(at 0 0 90)
			(size 0.508 0.508)
			(layers "F.Cu" "F.Mask" "F.Paste")
			(net "M_C_VREF")
		)
		(pad "2" smd rect
			(at 0 0.889 90)
			(size 0.508 0.508)
			(layers "F.Cu" "F.Mask" "F.Paste")
			(net "GND")
		)
		(zone
			(layer "F.Cu")
			(hatch none 0.5)
			(connect_pads
				(clearance 0)
			)
			(min_thickness 0.25)
			(keepout
				(tracks allowed)
				(vias not_allowed)
				(pads allowed)
				(copperpour not_allowed)
				(footprints allowed)
			)
			(placement
				(enabled no)
				(sheetname "")
			)
			(fill
				(thermal_gap 0.5)
				(thermal_bridge_width 0.5)
				(island_removal_mode 0)
			)
			(polygon
				(pts
					(xy 195.834 -3.067812) (xy 195.834 -3.575812) (xy 196.215 -3.575812) (xy 196.215 -3.067812)
				)
			)
		)
		(zone
			(layer "F.Cu")
			(hatch none 0.5)
			(connect_pads
				(clearance 0)
			)
			(min_thickness 0.25)
			(keepout
				(tracks not_allowed)
				(vias allowed)
				(pads allowed)
				(copperpour not_allowed)
				(footprints allowed)
			)
			(placement
				(enabled no)
				(sheetname "")
			)
			(fill
				(thermal_gap 0.5)
				(thermal_bridge_width 0.5)
				(island_removal_mode 0)
			)
			(polygon
				(pts
					(xy 196.215 -3.067812) (xy 196.215 -3.575812) (xy 195.834 -3.575812) (xy 195.834 -3.067812)
				)
			)
		)
	)
	(footprint ""
		(layer "F.Cu")
		(at 229.23881 -164.911786 90)
		(property "Reference" "T1D14"
			(at 0 0 90)
			(layer "F.SilkS")
			(hide yes)
			(effects
				(font
					(size 1.27 1.27)
				)
			)
		)
		(property "Value" "*"
			(at -3.4036 -4.46405 90)
			(unlocked yes)
			(layer "F.Fab")
			(hide yes)
			(effects
				(font
					(size 0.889 0.889)
					(thickness 0.1524)
				)
			)
		)
		(property "Device Type" "TEST-PAD-12P-1-GP-U_DISCRET-GBA"
			(at -3.4036 -5.98805 90)
			(unlocked yes)
			(layer "F.Fab")
			(hide yes)
			(effects
				(font
					(size 0.889 0.889)
					(thickness 0.1524)
				)
			)
		)
		(duplicate_pad_numbers_are_jumpers no)
		(fp_line
			(start 2.3622 -4.826)
			(end 2.3622 3.4798)
			(stroke
				(width 0.1524)
				(type default)
			)
			(layer "F.SilkS")
		)
		(fp_line
			(start -2.3876 -4.826)
			(end 2.3622 -4.826)
			(stroke
				(width 0.1524)
				(type default)
			)
			(layer "F.SilkS")
		)
		(fp_line
			(start 2.3622 3.4798)
			(end -2.3876 3.4798)
			(stroke
				(width 0.1524)
				(type default)
			)
			(layer "F.SilkS")
		)
		(fp_line
			(start -2.3876 3.4798)
			(end -2.3876 -4.826)
			(stroke
				(width 0.1524)
				(type default)
			)
			(layer "F.SilkS")
		)
		(fp_rect
			(start -2.6416 3.7338)
			(end 2.6162 -5.08)
			(stroke
				(width 0)
				(type default)
			)
			(fill no)
			(layer "F.CrtYd")
		)
		(fp_rect
			(start -2.6416 3.7338)
			(end 2.6162 -5.08)
			(stroke
				(width 0)
				(type default)
			)
			(fill no)
			(layer "F.Fab")
		)
		(pad "1" smd circle
			(at 0.496824 -1.301496 90)
			(size 0.6604 0.6604)
			(layers "F.Cu" "F.Mask" "F.Paste")
			(net "L1_85OHM_10INCH_DN")
		)
		(pad "2" smd circle
			(at -0.503936 -1.301496 90)
			(size 0.6604 0.6604)
			(layers "F.Cu" "F.Mask" "F.Paste")
			(net "L1_85OHM_10INCH_DP")
		)
		(pad "3" smd custom
			(at -0.00889 0.370078 90)
			(size 0.74295 0.74295)
			(layers "F.Cu" "F.Mask" "F.Paste")
			(net "GND")
			(options
				(clearance outline)
				(anchor circle)
			)
			(primitives
				(gr_poly
					(pts
						(xy -2.1209 1.4859) (xy 2.1209 1.4859) (xy 2.1209 -1.4859) (xy 1.08585 -1.4859) (xy 1.08585 -0.4699)
						(xy -1.08585 -0.4699) (xy -1.08585 -1.4859) (xy -2.1209 -1.4859)
					)
					(width 0)
					(fill yes)
				)
			)
		)
		(pad "4" thru_hole circle
			(at 1.266444 -3.851656 90)
			(size 1.4478 1.4478)
			(drill 1.0414)
			(layers "*.Cu" "*.Mask")
			(remove_unused_layers no)
			(net "GND")
			(clearance 0.1524)
			(thermal_gap 0.1524)
		)
		(pad "5" thru_hole circle
			(at -1.273556 -3.851656 90)
			(size 1.4478 1.4478)
			(drill 1.0414)
			(layers "*.Cu" "*.Mask")
			(remove_unused_layers no)
			(net "GND")
			(clearance 0.1524)
			(thermal_gap 0.1524)
		)
		(pad "6" thru_hole circle
			(at 1.266444 2.498344 90)
			(size 1.4478 1.4478)
			(drill 1.0414)
			(layers "*.Cu" "*.Mask")
			(remove_unused_layers no)
			(net "GND")
			(clearance 0.1524)
			(thermal_gap 0.1524)
		)
		(pad "7" thru_hole circle
			(at -1.273556 2.498344 90)
			(size 1.4478 1.4478)
			(drill 1.0414)
			(layers "*.Cu" "*.Mask")
			(remove_unused_layers no)
			(net "GND")
			(clearance 0.1524)
			(thermal_gap 0.1524)
		)
		(pad "8" thru_hole circle
			(at 1.27 -0.4572 90)
			(size 0.7112 0.7112)
			(drill 0.4064)
			(layers "*.Cu" "*.Mask")
			(remove_unused_layers no)
			(net "GND")
			(clearance 0.1016)
			(thermal_gap 0.1016)
		)
		(pad "9" thru_hole circle
			(at 1.27 0.762 90)
			(size 0.7112 0.7112)
			(drill 0.4064)
			(layers "*.Cu" "*.Mask")
			(remove_unused_layers no)
			(net "GND")
			(clearance 0.1016)
			(thermal_gap 0.1016)
		)
		(pad "10" thru_hole circle
			(at -0.0254 0.762 90)
			(size 0.7112 0.7112)
			(drill 0.4064)
			(layers "*.Cu" "*.Mask")
			(remove_unused_layers no)
			(net "GND")
			(clearance 0.1016)
			(thermal_gap 0.1016)
		)
		(pad "11" thru_hole circle
			(at -1.27 0.762 90)
			(size 0.7112 0.7112)
			(drill 0.4064)
			(layers "*.Cu" "*.Mask")
			(remove_unused_layers no)
			(net "GND")
			(clearance 0.1016)
			(thermal_gap 0.1016)
		)
		(pad "12" thru_hole circle
			(at -1.27 -0.4572 90)
			(size 0.7112 0.7112)
			(drill 0.4064)
			(layers "*.Cu" "*.Mask")
			(remove_unused_layers no)
			(net "GND")
			(clearance 0.1016)
			(thermal_gap 0.1016)
		)
	)
)
